FILE_TYPE = MACRO_DRAWING;
SET COLOR_WIRE YELLOW;
SET COLOR_PROP ORANGE;
SET COLOR_DOT WHITE;
SET COLOR_ARC YELLOW;
SET COLOR_BODY GREEN;
SET COLOR_NOTE PURPLE;
SET PROP_DISPLAY VALUE;
SET PAGE_NUMBER P3;
FORCEADD QUANTA_TITLE_BLOCK_C..2
(-100 100);
FORCEPROP 1 LAST Q_TITLE TABLE OF CONTENT 2/3
J 0
(-9416 151);
DISPLAY 2.446809 (-9416 151);
PAINT GREEN (-9416 151);
FORCEPROP 1 LAST CUSTOM_TXT_CDS <CON_TC_SNO167>
J 2
(-5300 5075);
FORCEPROP 1 LAST CUSTOM_TXT_CDS <CON_TC_SNM172>
J 0
(-5200 4575);
FORCEPROP 1 LAST CUSTOM_TXT_CDS <CON_TC_SNM207>
J 0
(-2700 5075);
FORCEPROP 1 LAST CUSTOM_TXT_CDS <CON_TC_SNM206>
J 0
(-2700 5175);
FORCEPROP 1 LAST CUSTOM_TXT_CDS <CON_TC_SNM205>
J 0
(-2700 5275);
FORCEPROP 1 LAST CUSTOM_TXT_CDS <CON_TC_SNM202>
J 0
(-2700 5575);
FORCEPROP 2 LAST CUSTOM_TXT_CDS <NAME_1>
J 0
(-3300 275);
DISPLAY 1.021277 (-3300 275);
FORCEPROP 2 LAST CUSTOM_TXT_CDS <NAME_2>
J 0
(-3300 150);
DISPLAY 1.021277 (-3300 150);
FORCEPROP 1 LAST CUSTOM_TXT_CDS <CON_TC_SNO200>
J 2
(-5300 1775);
FORCEPROP 1 LAST CUSTOM_TXT_CDS <CON_TC_SNM149>
J 0
(-7700 2875);
FORCEPROP 1 LAST CUSTOM_TXT_CDS <CON_TC_SNO197>
J 2
(-5300 2075);
FORCEPROP 1 LAST CUSTOM_TXT_CDS <Q_NUMBER>
J 0
(-1500 200);
DISPLAY 1.212766 (-1500 200);
FORCEPROP 1 LAST CUSTOM_TXT_CDS <CON_LAST_MODIFIED>
J 0
(-2000 125);
DISPLAY 0.978723 (-2000 125);
FORCEPROP 1 LAST CUSTOM_TXT_CDS <Q_PROJ>
J 0
(-2475 200);
DISPLAY 1.212766 (-2475 200);
FORCEPROP 1 LAST CUSTOM_TXT_CDS <Q_REV>
J 0
(-275 200);
DISPLAY 1.212766 (-275 200);
FORCEPROP 1 LAST CUSTOM_TXT_CDS <CON_PAGE_NUM> OF <CON_TOTAL_PAGES>
J 0
(-538 113);
DISPLAY 0.978723 (-538 113);
FORCEPROP 1 LAST CUSTOM_TXT_CDS <CON_TC_SNM121>
J 0
(-7700 5675);
FORCEPROP 1 LAST CUSTOM_TXT_CDS <CON_TC_SNM122>
J 0
(-7700 5575);
FORCEPROP 1 LAST CUSTOM_TXT_CDS <CON_TC_SNM123>
J 0
(-7700 5475);
FORCEPROP 1 LAST CUSTOM_TXT_CDS <CON_TC_SNM124>
J 0
(-7700 5375);
FORCEPROP 1 LAST CUSTOM_TXT_CDS <CON_TC_SNM125>
J 0
(-7700 5275);
FORCEPROP 1 LAST CUSTOM_TXT_CDS <CON_TC_SNM126>
J 0
(-7700 5175);
FORCEPROP 1 LAST CUSTOM_TXT_CDS <CON_TC_SNM127>
J 0
(-7700 5075);
FORCEPROP 1 LAST CUSTOM_TXT_CDS <CON_TC_SNM128>
J 0
(-7700 4975);
FORCEPROP 1 LAST CUSTOM_TXT_CDS <CON_TC_SNM129>
J 0
(-7700 4875);
FORCEPROP 1 LAST CUSTOM_TXT_CDS <CON_TC_SNM130>
J 0
(-7700 4775);
FORCEPROP 1 LAST CUSTOM_TXT_CDS <CON_TC_SNM131>
J 0
(-7700 4675);
FORCEPROP 1 LAST CUSTOM_TXT_CDS <CON_TC_SNM132>
J 0
(-7700 4575);
FORCEPROP 1 LAST CUSTOM_TXT_CDS <CON_TC_SNM133>
J 0
(-7700 4475);
FORCEPROP 1 LAST CUSTOM_TXT_CDS <CON_TC_SNM134>
J 0
(-7700 4375);
FORCEPROP 1 LAST CUSTOM_TXT_CDS <CON_TC_SNM135>
J 0
(-7700 4275);
FORCEPROP 1 LAST CUSTOM_TXT_CDS <CON_TC_SNM136>
J 0
(-7700 4175);
FORCEPROP 1 LAST CUSTOM_TXT_CDS <CON_TC_SNM137>
J 0
(-7700 4075);
FORCEPROP 1 LAST CUSTOM_TXT_CDS <CON_TC_SNM138>
J 0
(-7700 3975);
FORCEPROP 1 LAST CUSTOM_TXT_CDS <CON_TC_SNM139>
J 0
(-7700 3875);
FORCEPROP 1 LAST CUSTOM_TXT_CDS <CON_TC_SNM140>
J 0
(-7700 3775);
FORCEPROP 1 LAST CUSTOM_TXT_CDS <CON_TC_SNM141>
J 0
(-7700 3675);
FORCEPROP 1 LAST CUSTOM_TXT_CDS <CON_TC_SNM142>
J 0
(-7700 3575);
FORCEPROP 1 LAST CUSTOM_TXT_CDS <CON_TC_SNM143>
J 0
(-7700 3475);
FORCEPROP 1 LAST CUSTOM_TXT_CDS <CON_TC_SNM144>
J 0
(-7700 3375);
FORCEPROP 1 LAST CUSTOM_TXT_CDS <CON_TC_SNM145>
J 0
(-7700 3275);
FORCEPROP 1 LAST CUSTOM_TXT_CDS <CON_TC_SNM146>
J 0
(-7700 3175);
FORCEPROP 1 LAST CUSTOM_TXT_CDS <CON_TC_SNM147>
J 0
(-7700 3075);
FORCEPROP 1 LAST CUSTOM_TXT_CDS <CON_TC_SNM148>
J 0
(-7700 2975);
FORCEPROP 1 LAST CUSTOM_TXT_CDS <CON_TC_SNM150>
J 0
(-7700 2775);
FORCEPROP 1 LAST CUSTOM_TXT_CDS <CON_TC_SNM151>
J 0
(-7700 2675);
FORCEPROP 1 LAST CUSTOM_TXT_CDS <CON_TC_SNM152>
J 0
(-7700 2575);
FORCEPROP 1 LAST CUSTOM_TXT_CDS <CON_TC_SNM153>
J 0
(-7700 2475);
FORCEPROP 1 LAST CUSTOM_TXT_CDS <CON_TC_SNM154>
J 0
(-7700 2375);
FORCEPROP 1 LAST CUSTOM_TXT_CDS <CON_TC_SNM155>
J 0
(-7700 2275);
FORCEPROP 1 LAST CUSTOM_TXT_CDS <CON_TC_SNM156>
J 0
(-7700 2175);
FORCEPROP 1 LAST CUSTOM_TXT_CDS <CON_TC_SNM157>
J 0
(-7700 2075);
FORCEPROP 1 LAST CUSTOM_TXT_CDS <CON_TC_SNM158>
J 0
(-7700 1975);
FORCEPROP 1 LAST CUSTOM_TXT_CDS <CON_TC_SNM159>
J 0
(-7700 1875);
FORCEPROP 1 LAST CUSTOM_TXT_CDS <CON_TC_SNM160>
J 0
(-7700 1775);
FORCEPROP 1 LAST CUSTOM_TXT_CDS <CON_TC_SNM161>
J 0
(-5200 5675);
FORCEPROP 1 LAST CUSTOM_TXT_CDS <CON_TC_SNM162>
J 0
(-5200 5575);
FORCEPROP 1 LAST CUSTOM_TXT_CDS <CON_TC_SNM163>
J 0
(-5200 5475);
FORCEPROP 1 LAST CUSTOM_TXT_CDS <CON_TC_SNM164>
J 0
(-5200 5375);
FORCEPROP 1 LAST CUSTOM_TXT_CDS <CON_TC_SNM165>
J 0
(-5200 5275);
FORCEPROP 1 LAST CUSTOM_TXT_CDS <CON_TC_SNM166>
J 0
(-5200 5175);
FORCEPROP 1 LAST CUSTOM_TXT_CDS <CON_TC_SNM167>
J 0
(-5200 5075);
FORCEPROP 1 LAST CUSTOM_TXT_CDS <CON_TC_SNM168>
J 0
(-5200 4975);
FORCEPROP 1 LAST CUSTOM_TXT_CDS <CON_TC_SNM169>
J 0
(-5200 4875);
FORCEPROP 1 LAST CUSTOM_TXT_CDS <CON_TC_SNM170>
J 0
(-5200 4775);
FORCEPROP 1 LAST CUSTOM_TXT_CDS <CON_TC_SNM171>
J 0
(-5200 4675);
FORCEPROP 1 LAST CUSTOM_TXT_CDS <CON_TC_SNM173>
J 0
(-5200 4475);
FORCEPROP 1 LAST CUSTOM_TXT_CDS <CON_TC_SNM174>
J 0
(-5200 4375);
FORCEPROP 1 LAST CUSTOM_TXT_CDS <CON_TC_SNM175>
J 0
(-5200 4275);
FORCEPROP 1 LAST CUSTOM_TXT_CDS <CON_TC_SNM176>
J 0
(-5200 4175);
FORCEPROP 1 LAST CUSTOM_TXT_CDS <CON_TC_SNM177>
J 0
(-5200 4075);
FORCEPROP 1 LAST CUSTOM_TXT_CDS <CON_TC_SNM178>
J 0
(-5200 3975);
FORCEPROP 1 LAST CUSTOM_TXT_CDS <CON_TC_SNM179>
J 0
(-5200 3875);
FORCEPROP 1 LAST CUSTOM_TXT_CDS <CON_TC_SNM180>
J 0
(-5200 3775);
FORCEPROP 1 LAST CUSTOM_TXT_CDS <CON_TC_SNM181>
J 0
(-5200 3675);
FORCEPROP 1 LAST CUSTOM_TXT_CDS <CON_TC_SNM182>
J 0
(-5200 3575);
FORCEPROP 1 LAST CUSTOM_TXT_CDS <CON_TC_SNM183>
J 0
(-5200 3475);
FORCEPROP 1 LAST CUSTOM_TXT_CDS <CON_TC_SNM184>
J 0
(-5200 3375);
FORCEPROP 1 LAST CUSTOM_TXT_CDS <CON_TC_SNM185>
J 0
(-5200 3275);
FORCEPROP 1 LAST CUSTOM_TXT_CDS <CON_TC_SNM186>
J 0
(-5200 3175);
FORCEPROP 1 LAST CUSTOM_TXT_CDS <CON_TC_SNM187>
J 0
(-5200 3075);
FORCEPROP 1 LAST CUSTOM_TXT_CDS <CON_TC_SNM188>
J 0
(-5200 2975);
FORCEPROP 1 LAST CUSTOM_TXT_CDS <CON_TC_SNM189>
J 0
(-5200 2875);
FORCEPROP 1 LAST CUSTOM_TXT_CDS <CON_TC_SNM190>
J 0
(-5200 2775);
FORCEPROP 1 LAST CUSTOM_TXT_CDS <CON_TC_SNM191>
J 0
(-5200 2675);
FORCEPROP 1 LAST CUSTOM_TXT_CDS <CON_TC_SNM192>
J 0
(-5200 2575);
FORCEPROP 1 LAST CUSTOM_TXT_CDS <CON_TC_SNM193>
J 0
(-5200 2475);
FORCEPROP 1 LAST CUSTOM_TXT_CDS <CON_TC_SNM194>
J 0
(-5200 2375);
FORCEPROP 1 LAST CUSTOM_TXT_CDS <CON_TC_SNM195>
J 0
(-5200 2275);
FORCEPROP 1 LAST CUSTOM_TXT_CDS <CON_TC_SNM196>
J 0
(-5200 2175);
FORCEPROP 1 LAST CUSTOM_TXT_CDS <CON_TC_SNM197>
J 0
(-5200 2075);
FORCEPROP 1 LAST CUSTOM_TXT_CDS <CON_TC_SNM198>
J 0
(-5200 1975);
FORCEPROP 1 LAST CUSTOM_TXT_CDS <CON_TC_SNM199>
J 0
(-5200 1875);
FORCEPROP 1 LAST CUSTOM_TXT_CDS <CON_TC_SNM200>
J 0
(-5200 1775);
FORCEPROP 1 LAST CUSTOM_TXT_CDS <CON_TC_SNM201>
J 0
(-2700 5675);
FORCEPROP 1 LAST CUSTOM_TXT_CDS <CON_TC_SNM203>
J 0
(-2700 5475);
FORCEPROP 1 LAST CUSTOM_TXT_CDS <CON_TC_SNM204>
J 0
(-2700 5375);
FORCEPROP 1 LAST CUSTOM_TXT_CDS <CON_TC_SNM208>
J 0
(-2700 4975);
FORCEPROP 1 LAST CUSTOM_TXT_CDS <CON_TC_SNM209>
J 0
(-2700 4875);
FORCEPROP 1 LAST CUSTOM_TXT_CDS <CON_TC_SNM210>
J 0
(-2700 4775);
FORCEPROP 1 LAST CUSTOM_TXT_CDS <CON_TC_SNM211>
J 0
(-2700 4675);
FORCEPROP 1 LAST CUSTOM_TXT_CDS <CON_TC_SNM212>
J 0
(-2700 4575);
FORCEPROP 1 LAST CUSTOM_TXT_CDS <CON_TC_SNM213>
J 0
(-2700 4475);
FORCEPROP 1 LAST CUSTOM_TXT_CDS <CON_TC_SNM214>
J 0
(-2700 4375);
FORCEPROP 1 LAST CUSTOM_TXT_CDS <CON_TC_SNM215>
J 0
(-2700 4275);
FORCEPROP 1 LAST CUSTOM_TXT_CDS <CON_TC_SNM216>
J 0
(-2700 4175);
FORCEPROP 1 LAST CUSTOM_TXT_CDS <CON_TC_SNM217>
J 0
(-2700 4075);
FORCEPROP 1 LAST CUSTOM_TXT_CDS <CON_TC_SNM218>
J 0
(-2700 3975);
FORCEPROP 1 LAST CUSTOM_TXT_CDS <CON_TC_SNM219>
J 0
(-2700 3875);
FORCEPROP 1 LAST CUSTOM_TXT_CDS <CON_TC_SNM220>
J 0
(-2700 3775);
FORCEPROP 1 LAST CUSTOM_TXT_CDS <CON_TC_SNM221>
J 0
(-2700 3675);
FORCEPROP 1 LAST CUSTOM_TXT_CDS <CON_TC_SNM222>
J 0
(-2700 3575);
FORCEPROP 1 LAST CUSTOM_TXT_CDS <CON_TC_SNM223>
J 0
(-2700 3475);
FORCEPROP 1 LAST CUSTOM_TXT_CDS <CON_TC_SNM224>
J 0
(-2700 3375);
FORCEPROP 1 LAST CUSTOM_TXT_CDS <CON_TC_SNM225>
J 0
(-2700 3275);
FORCEPROP 1 LAST CUSTOM_TXT_CDS <CON_TC_SNM226>
J 0
(-2700 3175);
FORCEPROP 1 LAST CUSTOM_TXT_CDS <CON_TC_SNM227>
J 0
(-2700 3075);
FORCEPROP 1 LAST CUSTOM_TXT_CDS <CON_TC_SNM228>
J 0
(-2700 2975);
FORCEPROP 1 LAST CUSTOM_TXT_CDS <CON_TC_SNM229>
J 0
(-2700 2875);
FORCEPROP 1 LAST CUSTOM_TXT_CDS <CON_TC_SNM230>
J 0
(-2700 2775);
FORCEPROP 1 LAST CUSTOM_TXT_CDS <CON_TC_SNM231>
J 0
(-2700 2675);
FORCEPROP 1 LAST CUSTOM_TXT_CDS <CON_TC_SNM232>
J 0
(-2700 2575);
FORCEPROP 1 LAST CUSTOM_TXT_CDS <CON_TC_SNM233>
J 0
(-2700 2475);
FORCEPROP 1 LAST CUSTOM_TXT_CDS <CON_TC_SNM234>
J 0
(-2700 2375);
FORCEPROP 1 LAST CUSTOM_TXT_CDS <CON_TC_SNM235>
J 0
(-2700 2275);
FORCEPROP 1 LAST CUSTOM_TXT_CDS <CON_TC_SNM236>
J 0
(-2700 2175);
FORCEPROP 1 LAST CUSTOM_TXT_CDS <CON_TC_SNM237>
J 0
(-2700 2075);
FORCEPROP 1 LAST CUSTOM_TXT_CDS <CON_TC_SNM238>
J 0
(-2700 1975);
FORCEPROP 1 LAST CUSTOM_TXT_CDS <CON_TC_SNM239>
J 0
(-2700 1875);
FORCEPROP 1 LAST CUSTOM_TXT_CDS <CON_TC_SNM240>
J 0
(-2700 1775);
FORCEPROP 1 LAST CUSTOM_TXT_CDS <CON_TC_SNO121>
J 2
(-7800 5675);
FORCEPROP 1 LAST CUSTOM_TXT_CDS <CON_TC_SNO122>
J 2
(-7800 5575);
FORCEPROP 1 LAST CUSTOM_TXT_CDS <CON_TC_SNO123>
J 2
(-7800 5475);
FORCEPROP 1 LAST CUSTOM_TXT_CDS <CON_TC_SNO124>
J 2
(-7800 5375);
FORCEPROP 1 LAST CUSTOM_TXT_CDS <CON_TC_SNO125>
J 2
(-7800 5275);
FORCEPROP 1 LAST CUSTOM_TXT_CDS <CON_TC_SNO126>
J 2
(-7800 5175);
FORCEPROP 1 LAST CUSTOM_TXT_CDS <CON_TC_SNO127>
J 2
(-7800 5075);
FORCEPROP 1 LAST CUSTOM_TXT_CDS <CON_TC_SNO128>
J 2
(-7800 4975);
FORCEPROP 1 LAST CUSTOM_TXT_CDS <CON_TC_SNO129>
J 2
(-7800 4875);
FORCEPROP 1 LAST CUSTOM_TXT_CDS <CON_TC_SNO130>
J 2
(-7800 4775);
FORCEPROP 1 LAST CUSTOM_TXT_CDS <CON_TC_SNO131>
J 2
(-7800 4675);
FORCEPROP 1 LAST CUSTOM_TXT_CDS <CON_TC_SNO132>
J 2
(-7800 4575);
FORCEPROP 1 LAST CUSTOM_TXT_CDS <CON_TC_SNO133>
J 2
(-7800 4475);
FORCEPROP 1 LAST CUSTOM_TXT_CDS <CON_TC_SNO134>
J 2
(-7800 4375);
FORCEPROP 1 LAST CUSTOM_TXT_CDS <CON_TC_SNO135>
J 2
(-7800 4275);
FORCEPROP 1 LAST CUSTOM_TXT_CDS <CON_TC_SNO136>
J 2
(-7800 4175);
FORCEPROP 1 LAST CUSTOM_TXT_CDS <CON_TC_SNO137>
J 2
(-7800 4075);
FORCEPROP 1 LAST CUSTOM_TXT_CDS <CON_TC_SNO138>
J 2
(-7800 3975);
FORCEPROP 1 LAST CUSTOM_TXT_CDS <CON_TC_SNO139>
J 2
(-7800 3875);
FORCEPROP 1 LAST CUSTOM_TXT_CDS <CON_TC_SNO140>
J 2
(-7800 3775);
FORCEPROP 1 LAST CUSTOM_TXT_CDS <CON_TC_SNO141>
J 2
(-7800 3675);
FORCEPROP 1 LAST CUSTOM_TXT_CDS <CON_TC_SNO142>
J 2
(-7800 3575);
FORCEPROP 1 LAST CUSTOM_TXT_CDS <CON_TC_SNO143>
J 2
(-7800 3475);
FORCEPROP 1 LAST CUSTOM_TXT_CDS <CON_TC_SNO144>
J 2
(-7800 3375);
FORCEPROP 1 LAST CUSTOM_TXT_CDS <CON_TC_SNO145>
J 2
(-7800 3275);
FORCEPROP 1 LAST CUSTOM_TXT_CDS <CON_TC_SNO146>
J 2
(-7800 3175);
FORCEPROP 1 LAST CUSTOM_TXT_CDS <CON_TC_SNO147>
J 2
(-7800 3075);
FORCEPROP 1 LAST CUSTOM_TXT_CDS <CON_TC_SNO148>
J 2
(-7800 2975);
FORCEPROP 1 LAST CUSTOM_TXT_CDS <CON_TC_SNO149>
J 2
(-7800 2875);
FORCEPROP 1 LAST CUSTOM_TXT_CDS <CON_TC_SNO150>
J 2
(-7800 2775);
FORCEPROP 1 LAST CUSTOM_TXT_CDS <CON_TC_SNO151>
J 2
(-7800 2675);
FORCEPROP 1 LAST CUSTOM_TXT_CDS <CON_TC_SNO152>
J 2
(-7800 2575);
FORCEPROP 1 LAST CUSTOM_TXT_CDS <CON_TC_SNO153>
J 2
(-7800 2475);
FORCEPROP 1 LAST CUSTOM_TXT_CDS <CON_TC_SNO154>
J 2
(-7800 2375);
FORCEPROP 1 LAST CUSTOM_TXT_CDS <CON_TC_SNO155>
J 2
(-7800 2275);
FORCEPROP 1 LAST CUSTOM_TXT_CDS <CON_TC_SNO156>
J 2
(-7800 2175);
FORCEPROP 1 LAST CUSTOM_TXT_CDS <CON_TC_SNO157>
J 2
(-7800 2075);
FORCEPROP 1 LAST CUSTOM_TXT_CDS <CON_TC_SNO158>
J 2
(-7800 1975);
FORCEPROP 1 LAST CUSTOM_TXT_CDS <CON_TC_SNO159>
J 2
(-7800 1875);
FORCEPROP 1 LAST CUSTOM_TXT_CDS <CON_TC_SNO160>
J 2
(-7800 1775);
FORCEPROP 1 LAST CUSTOM_TXT_CDS <CON_TC_SNO161>
J 2
(-5300 5675);
FORCEPROP 1 LAST CUSTOM_TXT_CDS <CON_TC_SNO162>
J 2
(-5300 5575);
FORCEPROP 1 LAST CUSTOM_TXT_CDS <CON_TC_SNO163>
J 2
(-5300 5475);
FORCEPROP 1 LAST CUSTOM_TXT_CDS <CON_TC_SNO164>
J 2
(-5300 5375);
FORCEPROP 1 LAST CUSTOM_TXT_CDS <CON_TC_SNO165>
J 2
(-5300 5275);
FORCEPROP 1 LAST CUSTOM_TXT_CDS <CON_TC_SNO166>
J 2
(-5300 5175);
FORCEPROP 1 LAST CUSTOM_TXT_CDS <CON_TC_SNO168>
J 2
(-5300 4975);
FORCEPROP 1 LAST CUSTOM_TXT_CDS <CON_TC_SNO169>
J 2
(-5300 4875);
FORCEPROP 1 LAST CUSTOM_TXT_CDS <CON_TC_SNO170>
J 2
(-5300 4775);
FORCEPROP 1 LAST CUSTOM_TXT_CDS <CON_TC_SNO171>
J 2
(-5300 4675);
FORCEPROP 1 LAST CUSTOM_TXT_CDS <CON_TC_SNO172>
J 2
(-5300 4575);
FORCEPROP 1 LAST CUSTOM_TXT_CDS <CON_TC_SNO173>
J 2
(-5300 4475);
FORCEPROP 1 LAST CUSTOM_TXT_CDS <CON_TC_SNO174>
J 2
(-5300 4375);
FORCEPROP 1 LAST CUSTOM_TXT_CDS <CON_TC_SNO175>
J 2
(-5300 4275);
FORCEPROP 1 LAST CUSTOM_TXT_CDS <CON_TC_SNO176>
J 2
(-5300 4175);
FORCEPROP 1 LAST CUSTOM_TXT_CDS <CON_TC_SNO177>
J 2
(-5300 4075);
FORCEPROP 1 LAST CUSTOM_TXT_CDS <CON_TC_SNO178>
J 2
(-5300 3975);
FORCEPROP 1 LAST CUSTOM_TXT_CDS <CON_TC_SNO179>
J 2
(-5300 3875);
FORCEPROP 1 LAST CUSTOM_TXT_CDS <CON_TC_SNO180>
J 2
(-5300 3775);
FORCEPROP 1 LAST CUSTOM_TXT_CDS <CON_TC_SNO181>
J 2
(-5300 3675);
FORCEPROP 1 LAST CUSTOM_TXT_CDS <CON_TC_SNO182>
J 2
(-5300 3575);
FORCEPROP 1 LAST CUSTOM_TXT_CDS <CON_TC_SNO183>
J 2
(-5300 3475);
FORCEPROP 1 LAST CUSTOM_TXT_CDS <CON_TC_SNO184>
J 2
(-5300 3375);
FORCEPROP 1 LAST CUSTOM_TXT_CDS <CON_TC_SNO185>
J 2
(-5300 3275);
FORCEPROP 1 LAST CUSTOM_TXT_CDS <CON_TC_SNO186>
J 2
(-5300 3175);
FORCEPROP 1 LAST CUSTOM_TXT_CDS <CON_TC_SNO187>
J 2
(-5300 3075);
FORCEPROP 1 LAST CUSTOM_TXT_CDS <CON_TC_SNO188>
J 2
(-5300 2975);
FORCEPROP 1 LAST CUSTOM_TXT_CDS <CON_TC_SNO189>
J 2
(-5300 2875);
FORCEPROP 1 LAST CUSTOM_TXT_CDS <CON_TC_SNO190>
J 2
(-5300 2775);
FORCEPROP 1 LAST CUSTOM_TXT_CDS <CON_TC_SNO191>
J 2
(-5300 2675);
FORCEPROP 1 LAST CUSTOM_TXT_CDS <CON_TC_SNO192>
J 2
(-5300 2575);
FORCEPROP 1 LAST CUSTOM_TXT_CDS <CON_TC_SNO193>
J 2
(-5300 2475);
FORCEPROP 1 LAST CUSTOM_TXT_CDS <CON_TC_SNO194>
J 2
(-5300 2375);
FORCEPROP 1 LAST CUSTOM_TXT_CDS <CON_TC_SNO195>
J 2
(-5300 2275);
FORCEPROP 1 LAST CUSTOM_TXT_CDS <CON_TC_SNO196>
J 2
(-5300 2175);
FORCEPROP 1 LAST CUSTOM_TXT_CDS <CON_TC_SNO198>
J 2
(-5300 1975);
FORCEPROP 1 LAST CUSTOM_TXT_CDS <CON_TC_SNO199>
J 2
(-5300 1875);
FORCEPROP 1 LAST CUSTOM_TXT_CDS <CON_TC_SNO201>
J 2
(-2800 5675);
FORCEPROP 1 LAST CUSTOM_TXT_CDS <CON_TC_SNO202>
J 2
(-2800 5575);
FORCEPROP 1 LAST CUSTOM_TXT_CDS <CON_TC_SNO203>
J 2
(-2800 5475);
FORCEPROP 1 LAST CUSTOM_TXT_CDS <CON_TC_SNO204>
J 2
(-2800 5375);
FORCEPROP 1 LAST CUSTOM_TXT_CDS <CON_TC_SNO205>
J 2
(-2800 5275);
FORCEPROP 1 LAST CUSTOM_TXT_CDS <CON_TC_SNO206>
J 2
(-2800 5175);
FORCEPROP 1 LAST CUSTOM_TXT_CDS <CON_TC_SNO207>
J 2
(-2800 5075);
FORCEPROP 1 LAST CUSTOM_TXT_CDS <CON_TC_SNO208>
J 2
(-2800 4975);
FORCEPROP 1 LAST CUSTOM_TXT_CDS <CON_TC_SNO209>
J 2
(-2800 4875);
FORCEPROP 1 LAST CUSTOM_TXT_CDS <CON_TC_SNO210>
J 2
(-2800 4775);
FORCEPROP 1 LAST CUSTOM_TXT_CDS <CON_TC_SNO211>
J 2
(-2800 4675);
FORCEPROP 1 LAST CUSTOM_TXT_CDS <CON_TC_SNO212>
J 2
(-2800 4575);
FORCEPROP 1 LAST CUSTOM_TXT_CDS <CON_TC_SNO213>
J 2
(-2800 4475);
FORCEPROP 1 LAST CUSTOM_TXT_CDS <CON_TC_SNO214>
J 2
(-2800 4375);
FORCEPROP 1 LAST CUSTOM_TXT_CDS <CON_TC_SNO215>
J 2
(-2800 4275);
FORCEPROP 1 LAST CUSTOM_TXT_CDS <CON_TC_SNO216>
J 2
(-2800 4175);
FORCEPROP 1 LAST CUSTOM_TXT_CDS <CON_TC_SNO217>
J 2
(-2800 4075);
FORCEPROP 1 LAST CUSTOM_TXT_CDS <CON_TC_SNO218>
J 2
(-2800 3975);
FORCEPROP 1 LAST CUSTOM_TXT_CDS <CON_TC_SNO219>
J 2
(-2800 3875);
FORCEPROP 1 LAST CUSTOM_TXT_CDS <CON_TC_SNO220>
J 2
(-2800 3775);
FORCEPROP 1 LAST CUSTOM_TXT_CDS <CON_TC_SNO221>
J 2
(-2800 3675);
FORCEPROP 1 LAST CUSTOM_TXT_CDS <CON_TC_SNO222>
J 2
(-2800 3575);
FORCEPROP 1 LAST CUSTOM_TXT_CDS <CON_TC_SNO223>
J 2
(-2800 3475);
FORCEPROP 1 LAST CUSTOM_TXT_CDS <CON_TC_SNO224>
J 2
(-2800 3375);
FORCEPROP 1 LAST CUSTOM_TXT_CDS <CON_TC_SNO225>
J 2
(-2800 3275);
FORCEPROP 1 LAST CUSTOM_TXT_CDS <CON_TC_SNO226>
J 2
(-2800 3175);
FORCEPROP 1 LAST CUSTOM_TXT_CDS <CON_TC_SNO227>
J 2
(-2800 3075);
FORCEPROP 1 LAST CUSTOM_TXT_CDS <CON_TC_SNO228>
J 2
(-2800 2975);
FORCEPROP 1 LAST CUSTOM_TXT_CDS <CON_TC_SNO229>
J 2
(-2800 2875);
FORCEPROP 1 LAST CUSTOM_TXT_CDS <CON_TC_SNO230>
J 2
(-2800 2775);
FORCEPROP 1 LAST CUSTOM_TXT_CDS <CON_TC_SNO231>
J 2
(-2800 2675);
FORCEPROP 1 LAST CUSTOM_TXT_CDS <CON_TC_SNO232>
J 2
(-2800 2575);
FORCEPROP 1 LAST CUSTOM_TXT_CDS <CON_TC_SNO233>
J 2
(-2800 2475);
FORCEPROP 1 LAST CUSTOM_TXT_CDS <CON_TC_SNO234>
J 2
(-2800 2375);
FORCEPROP 1 LAST CUSTOM_TXT_CDS <CON_TC_SNO235>
J 2
(-2800 2275);
FORCEPROP 1 LAST CUSTOM_TXT_CDS <CON_TC_SNO236>
J 2
(-2800 2175);
FORCEPROP 1 LAST CUSTOM_TXT_CDS <CON_TC_SNO237>
J 2
(-2800 2075);
FORCEPROP 1 LAST CUSTOM_TXT_CDS <CON_TC_SNO238>
J 2
(-2800 1975);
FORCEPROP 1 LAST CUSTOM_TXT_CDS <CON_TC_SNO239>
J 2
(-2800 1875);
FORCEPROP 1 LAST CUSTOM_TXT_CDS <CON_TC_SNO240>
J 2
(-2800 1775);
FORCEPROP 2 LAST CDS_LIB pure_quanta
J 0
(-100 100);
DISPLAY INVISIBLE (-100 100);
FORCEPROP 2 LAST PAGE_BORDER TRUE
J 0
(-7990 5350);
DISPLAY 0.638298 (-7990 5350);
PAINT PINK (-7990 5350);
DISPLAY INVISIBLE (-7990 5350);
FORCEPROP 1 LAST TOC_SYMBOL TRUE
J 0
(-9274 6552);
DISPLAY 0.978723 (-9274 6552);
PAINT GREEN (-9274 6552);
DISPLAY INVISIBLE (-9274 6552);
FORCEPROP 2 LAST CDS_XR_PAGE_TITLE CR-3 : @T6G_MB_LIB.T6G(SCH_1):PAGE3
J 0
(-7990 5350);
DISPLAY 0.638298 (-7990 5350);
PAINT PINK (-7990 5350);
DISPLAY INVISIBLE (-7990 5350);
FORCEPROP 2 LAST CUSTOM_TXT_CDS <XR_PAGE_TITLE>
J 0
(-7990 5350);
DISPLAY 0.638298 (-7990 5350);
PAINT PINK (-7990 5350);
DISPLAY INVISIBLE (-7990 5350);
FORCEPROP 1 LAST COMMENT_BODY TRUE
J 0
(-1249 126);
DISPLAY 0.978723 (-1249 126);
PAINT GREEN (-1249 126);
DISPLAY INVISIBLE (-1249 126);
FORCEPROP 1 LAST Q_DEPT BU9
J 1
(-3851 149);
DISPLAY 1.957447 (-3851 149);
PAINT GREEN (-3851 149);
DISPLAY INVISIBLE (-3851 149);
FORCEPROP 0 LAST CDS_CON_LAST_MODIFIED Thu Aug 24 10:13:29 2023
J 0
(-2000 125);
DISPLAY INVISIBLE (-2000 125);
QUIT
